(kicad_pcb
	(version 20260206)
	(generator "pcbnew")
	(generator_version "10.0")
	(general
		(thickness 1.6)
		(legacy_teardrops no)
	)
	(paper "A4")
	(title_block
		(title "dpb — 14545-sa.0730WZS0815.brd")
		(comment 1 "Honey Badger (Wiwynn) / footprint 438 of 1066 (CN7), pads 1-62 of 62")
	)
	(layers
		(0 "F.Cu" signal "TOP")
		(4 "In1.Cu" signal "L2GND")
		(6 "In2.Cu" signal "L3")
		(8 "In3.Cu" signal "L4VCC")
		(10 "In4.Cu" signal "L5VCC")
		(12 "In5.Cu" signal "L6")
		(14 "In6.Cu" signal "L7GND")
		(2 "B.Cu" signal "BOTTOM")
		(9 "F.Adhes" user "F.Adhesive")
		(11 "B.Adhes" user "B.Adhesive")
		(13 "F.Paste" user "Package Geometry/Pastemask Top")
		(15 "B.Paste" user "Package Geometry/Pastemask Bottom")
		(5 "F.SilkS" user "Ref Des/Silkscreen Top")
		(7 "B.SilkS" user "Ref Des/Silkscreen Bottom")
		(1 "F.Mask" user "Board Geometry/Soldermask Top")
		(3 "B.Mask" user "Board Geometry/Soldermask Bottom")
		(17 "Dwgs.User" user "User.Drawings")
		(19 "Cmts.User" user "User.Comments")
		(21 "Eco1.User" user "User.Eco1")
		(23 "Eco2.User" user "User.Eco2")
		(25 "Edge.Cuts" user "Board Geometry/Outline")
		(27 "Margin" user)
		(31 "F.CrtYd" user "Package Geometry/Place Bound Top")
		(29 "B.CrtYd" user "Package Geometry/Place Bound Bottom")
		(35 "F.Fab" user "Ref Des/Assembly Top")
		(33 "B.Fab" user "Ref Des/Assembly Bottom")
	)
	(footprint ""
		(layer "F.Cu")
		(at 258.899914 -409.949904 90)
		(property "Reference" "CN7"
			(at 0 0 90)
			(layer "F.SilkS")
			(hide yes)
			(effects
				(font
					(size 1.27 1.27)
				)
			)
		)
		(property "Value" "AMP-CONN60-5-GP"
			(at -32.935418 -14.620748 90)
			(unlocked yes)
			(layer "F.Fab")
			(hide yes)
			(effects
				(font
					(size 1.016 1.016)
					(thickness 0.1524)
				)
			)
		)
		(property "Device Type" "GPCE54362413HR"
			(at -32.935418 -16.144748 90)
			(unlocked yes)
			(layer "F.Fab")
			(hide yes)
			(effects
				(font
					(size 1.016 1.016)
					(thickness 0.1524)
				)
			)
		)
		(duplicate_pad_numbers_are_jumpers no)
		(pad "" np_thru_hole circle
			(at -50.279808 0 90)
			(size 0.254 0.254)
			(drill 3.7084)
			(layers "*.Cu" "*.Mask")
			(clearance 2.0828)
			(thermal_gap 2.0828)
		)
		(pad "" np_thru_hole circle
			(at 20.379944 0 90)
			(size 0.254 0.254)
			(drill 3.7084)
			(layers "*.Cu" "*.Mask")
			(clearance 2.0828)
			(thermal_gap 2.0828)
		)
		(pad "P1" smd rect
			(at -42.164 -8.377682 90)
			(size 0.0254 0.0254)
			(layers "F.Cu" "F.Mask" "F.Paste")
			(net "P12V")
		)
		(pad "P2" smd custom
			(at -41.060116 -8.377682 90)
			(size 2.3622 2.3622)
			(layers "F.Cu" "F.Mask" "F.Paste")
			(net "P12V")
			(options
				(clearance outline)
				(anchor circle)
			)
			(primitives
				(gr_poly
					(pts
						(xy -4.7244 5.0038) (xy -4.7244 -5.0038) (xy 4.7244 -5.0038) (xy 4.7244 5.0038) (xy 0.23495 5.0038)
						(xy 0.23495 -1.4986) (xy -0.23495 -1.4986) (xy -0.23495 5.0038)
					)
					(width 0)
					(fill yes)
				)
			)
		)
		(pad "P3" smd rect
			(at -39.878 -8.377682 90)
			(size 0.0254 0.0254)
			(layers "F.Cu" "F.Mask" "F.Paste")
			(net "P12V")
		)
		(pad "P4" smd rect
			(at -38.862 -8.377682 90)
			(size 0.0254 0.0254)
			(layers "F.Cu" "F.Mask" "F.Paste")
			(net "P12V")
		)
		(pad "P5" smd rect
			(at -32.004 -8.377682 90)
			(size 0.0254 0.0254)
			(layers "F.Cu" "F.Mask" "F.Paste")
			(net "P12V")
		)
		(pad "P6" smd custom
			(at -30.900116 -8.377682 90)
			(size 2.3622 2.3622)
			(layers "F.Cu" "F.Mask" "F.Paste")
			(net "P12V")
			(options
				(clearance outline)
				(anchor circle)
			)
			(primitives
				(gr_poly
					(pts
						(xy -4.7244 5.0038) (xy -4.7244 -5.0038) (xy 4.7244 -5.0038) (xy 4.7244 5.0038) (xy 0.23495 5.0038)
						(xy 0.23495 -1.4986) (xy -0.23495 -1.4986) (xy -0.23495 5.0038)
					)
					(width 0)
					(fill yes)
				)
			)
		)
		(pad "P7" smd rect
			(at -29.718 -8.377682 90)
			(size 0.0254 0.0254)
			(layers "F.Cu" "F.Mask" "F.Paste")
			(net "P12V")
		)
		(pad "P8" smd rect
			(at -28.702 -8.377682 90)
			(size 0.0254 0.0254)
			(layers "F.Cu" "F.Mask" "F.Paste")
			(net "P12V")
		)
		(pad "P9" smd rect
			(at -22.098 -8.377682 90)
			(size 0.0254 0.0254)
			(layers "F.Cu" "F.Mask" "F.Paste")
			(net "GND")
		)
		(pad "P10" smd custom
			(at -20.740116 -8.377682 90)
			(size 2.3622 2.3622)
			(layers "F.Cu" "F.Mask" "F.Paste")
			(net "GND")
			(options
				(clearance outline)
				(anchor circle)
			)
			(primitives
				(gr_poly
					(pts
						(xy -4.7244 5.0038) (xy -4.7244 -5.0038) (xy 4.7244 -5.0038) (xy 4.7244 5.0038) (xy 0.23495 5.0038)
						(xy 0.23495 -1.4986) (xy -0.23495 -1.4986) (xy -0.23495 5.0038)
					)
					(width 0)
					(fill yes)
				)
			)
		)
		(pad "P11" smd rect
			(at -19.558 -8.377682 90)
			(size 0.0254 0.0254)
			(layers "F.Cu" "F.Mask" "F.Paste")
			(net "GND")
		)
		(pad "P12" smd rect
			(at -18.542 -8.377682 90)
			(size 0.0254 0.0254)
			(layers "F.Cu" "F.Mask" "F.Paste")
			(net "GND")
		)
		(pad "P13" smd rect
			(at -11.938 -8.377682 90)
			(size 0.0254 0.0254)
			(layers "F.Cu" "F.Mask" "F.Paste")
			(net "GND")
		)
		(pad "P14" smd custom
			(at -10.580116 -8.377682 90)
			(size 2.3622 2.3622)
			(layers "F.Cu" "F.Mask" "F.Paste")
			(net "GND")
			(options
				(clearance outline)
				(anchor circle)
			)
			(primitives
				(gr_poly
					(pts
						(xy -4.7244 5.0038) (xy -4.7244 -5.0038) (xy 4.7244 -5.0038) (xy 4.7244 5.0038) (xy 0.23495 5.0038)
						(xy 0.23495 -1.4986) (xy -0.23495 -1.4986) (xy -0.23495 5.0038)
					)
					(width 0)
					(fill yes)
				)
			)
		)
		(pad "P15" smd rect
			(at -9.144 -8.377682 90)
			(size 0.0254 0.0254)
			(layers "F.Cu" "F.Mask" "F.Paste")
			(net "GND")
		)
		(pad "P16" smd rect
			(at -7.874 -8.377682 90)
			(size 0.0254 0.0254)
			(layers "F.Cu" "F.Mask" "F.Paste")
			(net "GND")
		)
		(pad "P17" smd rect
			(at -2.960116 -5.126736 90)
			(size 4.3688 10.0076)
			(drill
				(offset 0 -0.381)
			)
			(layers "F.Cu" "F.Mask" "F.Paste")
			(net "GND")
		)
		(pad "P18" smd rect
			(at -2.032 -5.126736 90)
			(size 0.0254 0.0254)
			(layers "F.Cu" "F.Mask" "F.Paste")
			(net "GND")
		)
		(pad "P19" smd rect
			(at -2.032 -5.507736 90)
			(size 0.0254 0.0254)
			(layers "F.Cu" "F.Mask" "F.Paste")
			(net "GND")
		)
		(pad "P20" smd rect
			(at -2.960116 -5.507736 90)
			(size 4.3688 10.0076)
			(layers "F.Cu" "F.Mask" "F.Paste")
			(net "GND")
		)
		(pad "P21" smd rect
			(at -7.874 -8.758682 90)
			(size 0.0254 0.0254)
			(layers "F.Cu" "F.Mask" "F.Paste")
			(net "GND")
		)
		(pad "P22" smd rect
			(at -9.144 -8.758682 90)
			(size 0.0254 0.0254)
			(layers "F.Cu" "F.Mask" "F.Paste")
			(net "GND")
		)
		(pad "P23" smd custom
			(at -10.580116 -8.758682 90)
			(size 2.3622 2.3622)
			(layers "F.Cu" "F.Mask" "F.Paste")
			(net "GND")
			(options
				(clearance outline)
				(anchor circle)
			)
			(primitives
				(gr_poly
					(pts
						(xy -4.7244 5.0038) (xy -4.7244 -5.0038) (xy 4.7244 -5.0038) (xy 4.7244 5.0038) (xy 0.23495 5.0038)
						(xy 0.23495 -1.4986) (xy -0.23495 -1.4986) (xy -0.23495 5.0038)
					)
					(width 0)
					(fill yes)
				)
			)
		)
		(pad "P24" smd rect
			(at -11.938 -8.758682 90)
			(size 0.0254 0.0254)
			(layers "F.Cu" "F.Mask" "F.Paste")
			(net "GND")
		)
		(pad "P25" smd rect
			(at -18.542 -8.758682 90)
			(size 0.0254 0.0254)
			(layers "F.Cu" "F.Mask" "F.Paste")
			(net "GND")
		)
		(pad "P26" smd rect
			(at -19.558 -8.758682 90)
			(size 0.0254 0.0254)
			(layers "F.Cu" "F.Mask" "F.Paste")
			(net "GND")
		)
		(pad "P27" smd custom
			(at -20.740116 -8.758682 90)
			(size 2.3622 2.3622)
			(layers "F.Cu" "F.Mask" "F.Paste")
			(net "GND")
			(options
				(clearance outline)
				(anchor circle)
			)
			(primitives
				(gr_poly
					(pts
						(xy -4.7244 5.0038) (xy -4.7244 -5.0038) (xy 4.7244 -5.0038) (xy 4.7244 5.0038) (xy 0.23495 5.0038)
						(xy 0.23495 -1.4986) (xy -0.23495 -1.4986) (xy -0.23495 5.0038)
					)
					(width 0)
					(fill yes)
				)
			)
		)
		(pad "P28" smd rect
			(at -22.098 -8.758682 90)
			(size 0.0254 0.0254)
			(layers "F.Cu" "F.Mask" "F.Paste")
			(net "GND")
		)
		(pad "P29" smd rect
			(at -28.702 -8.758682 90)
			(size 0.0254 0.0254)
			(layers "F.Cu" "F.Mask" "F.Paste")
			(net "P12V")
		)
		(pad "P30" smd rect
			(at -29.718 -8.758682 90)
			(size 0.0254 0.0254)
			(layers "F.Cu" "F.Mask" "F.Paste")
			(net "P12V")
		)
		(pad "P31" smd custom
			(at -30.900116 -8.758682 90)
			(size 2.3622 2.3622)
			(layers "F.Cu" "F.Mask" "F.Paste")
			(net "P12V")
			(options
				(clearance outline)
				(anchor circle)
			)
			(primitives
				(gr_poly
					(pts
						(xy -4.7244 5.0038) (xy -4.7244 -5.0038) (xy 4.7244 -5.0038) (xy 4.7244 5.0038) (xy 0.23495 5.0038)
						(xy 0.23495 -1.4986) (xy -0.23495 -1.4986) (xy -0.23495 5.0038)
					)
					(width 0)
					(fill yes)
				)
			)
		)
		(pad "P32" smd rect
			(at -32.004 -8.758682 90)
			(size 0.0254 0.0254)
			(layers "F.Cu" "F.Mask" "F.Paste")
			(net "P12V")
		)
		(pad "P33" smd rect
			(at -38.862 -8.758682 90)
			(size 0.0254 0.0254)
			(layers "F.Cu" "F.Mask" "F.Paste")
			(net "P12V")
		)
		(pad "P34" smd rect
			(at -39.878 -8.758682 90)
			(size 0.0254 0.0254)
			(layers "F.Cu" "F.Mask" "F.Paste")
			(net "P12V")
		)
		(pad "P35" smd custom
			(at -41.060116 -8.758682 90)
			(size 2.3622 2.3622)
			(layers "F.Cu" "F.Mask" "F.Paste")
			(net "P12V")
			(options
				(clearance outline)
				(anchor circle)
			)
			(primitives
				(gr_poly
					(pts
						(xy -4.7244 5.0038) (xy -4.7244 -5.0038) (xy 4.7244 -5.0038) (xy 4.7244 5.0038) (xy 0.23495 5.0038)
						(xy 0.23495 -1.4986) (xy -0.23495 -1.4986) (xy -0.23495 5.0038)
					)
					(width 0)
					(fill yes)
				)
			)
		)
		(pad "P36" smd rect
			(at -42.164 -8.758682 90)
			(size 0.0254 0.0254)
			(layers "F.Cu" "F.Mask" "F.Paste")
			(net "P12V")
		)
		(pad "S1" smd rect
			(at 1.810004 -3.805936 90)
			(size 0.8128 5.842)
			(drill
				(offset 0 0.381)
			)
			(layers "F.Cu" "F.Mask" "F.Paste")
			(net "GND")
		)
		(pad "S2" smd rect
			(at 3.080004 -3.805936 90)
			(size 0.8128 5.842)
			(drill
				(offset 0 0.381)
			)
			(layers "F.Cu" "F.Mask" "F.Paste")
			(net "P3V3")
		)
		(pad "S3" smd rect
			(at 4.350004 -3.805936 90)
			(size 0.8128 5.842)
			(drill
				(offset 0 0.381)
			)
			(layers "F.Cu" "F.Mask" "F.Paste")
			(net "P3V3")
		)
		(pad "S4" smd rect
			(at 5.620004 -3.805936 90)
			(size 0.8128 5.842)
			(drill
				(offset 0 0.381)
			)
			(layers "F.Cu" "F.Mask" "F.Paste")
			(net "PEER_TRAY_PRESENT")
		)
		(pad "S5" smd rect
			(at 6.890004 -3.805936 90)
			(size 0.8128 5.842)
			(drill
				(offset 0 0.381)
			)
			(layers "F.Cu" "F.Mask" "F.Paste")
			(net "PWM_EXP_B")
		)
		(pad "S6" smd rect
			(at 8.160004 -3.805936 90)
			(size 0.8128 5.842)
			(drill
				(offset 0 0.381)
			)
			(layers "F.Cu" "F.Mask" "F.Paste")
			(net "SELF_TRAY_PRESENT")
		)
		(pad "S7" smd rect
			(at 9.430004 -3.805936 90)
			(size 0.8128 5.842)
			(drill
				(offset 0 0.381)
			)
			(layers "F.Cu" "F.Mask" "F.Paste")
			(net "PWM_EXP_A")
		)
		(pad "S8" smd rect
			(at 10.700004 -3.805936 90)
			(size 0.8128 5.842)
			(drill
				(offset 0 0.381)
			)
			(layers "F.Cu" "F.Mask" "F.Paste")
			(net "GND")
		)
		(pad "S9" smd rect
			(at 11.970004 -3.805936 90)
			(size 0.8128 5.842)
			(drill
				(offset 0 0.381)
			)
			(layers "F.Cu" "F.Mask" "F.Paste")
			(net "I2C_C_SDA")
		)
		(pad "S10" smd rect
			(at 13.240004 -3.805936 90)
			(size 0.8128 5.842)
			(drill
				(offset 0 0.381)
			)
			(layers "F.Cu" "F.Mask" "F.Paste")
			(net "GND")
		)
		(pad "S11" smd rect
			(at 14.510004 -3.805936 90)
			(size 0.8128 5.842)
			(drill
				(offset 0 0.381)
			)
			(layers "F.Cu" "F.Mask" "F.Paste")
			(net "I2C_C_SCL")
		)
		(pad "S12" smd rect
			(at 15.780004 -3.805936 90)
			(size 0.8128 5.842)
			(drill
				(offset 0 0.381)
			)
			(layers "F.Cu" "F.Mask" "F.Paste")
			(net "GND")
		)
		(pad "S13" smd rect
			(at 15.780004 -3.424936 90)
			(size 0.8128 5.842)
			(layers "F.Cu" "F.Mask" "F.Paste")
			(net "GND")
		)
		(pad "S14" smd rect
			(at 14.510004 -3.424936 90)
			(size 0.8128 5.842)
			(layers "F.Cu" "F.Mask" "F.Paste")
			(net "SELF_1A&2A_HB")
		)
		(pad "S15" smd rect
			(at 13.240004 -3.424936 90)
			(size 0.8128 5.842)
			(layers "F.Cu" "F.Mask" "F.Paste")
			(net "SELF_1B&2B_HB")
		)
		(pad "S16" smd rect
			(at 11.970004 -3.424936 90)
			(size 0.8128 5.842)
			(layers "F.Cu" "F.Mask" "F.Paste")
			(net "TRAY_ID")
		)
		(pad "S17" smd rect
			(at 10.700004 -3.424936 90)
			(size 0.8128 5.842)
			(layers "F.Cu" "F.Mask" "F.Paste")
			(net "FCB_HW_REV")
		)
		(pad "S18" smd rect
			(at 9.430004 -3.424936 90)
			(size 0.8128 5.842)
			(layers "F.Cu" "F.Mask" "F.Paste")
			(net "SD_LATCH_RELEASE")
		)
		(pad "S19" smd rect
			(at 8.160004 -3.424936 90)
			(size 0.8128 5.842)
			(layers "F.Cu" "F.Mask" "F.Paste")
			(net "GND")
		)
		(pad "S20" smd rect
			(at 6.890004 -3.424936 90)
			(size 0.8128 5.842)
			(layers "F.Cu" "F.Mask" "F.Paste")
			(net "PEER_1A&2A_HB")
		)
		(pad "S21" smd rect
			(at 5.620004 -3.424936 90)
			(size 0.8128 5.842)
			(layers "F.Cu" "F.Mask" "F.Paste")
			(net "PEER_1B&2B_HB")
		)
		(pad "S22" smd rect
			(at 4.350004 -3.424936 90)
			(size 0.8128 5.842)
			(layers "F.Cu" "F.Mask" "F.Paste")
			(net "GND")
		)
		(pad "S23" smd rect
			(at 3.080004 -3.424936 90)
			(size 0.8128 5.842)
			(layers "F.Cu" "F.Mask" "F.Paste")
			(net "GND")
		)
		(pad "S24" smd rect
			(at 1.810004 -3.424936 90)
			(size 0.8128 5.842)
			(layers "F.Cu" "F.Mask" "F.Paste")
			(net "P5VA")
		)
	)
)
